(kicad_pcb
	(version 20260206)
	(generator "pcbnew")
	(generator_version "10.0")
	(general
		(thickness 1.6)
		(legacy_teardrops no)
	)
	(paper "A4")
	(title_block
		(title "baseboard — 13948-1b.1110WZS1818.brd")
		(comment 1 "Honey Badger (Wiwynn) / footprints 2142-2150 of 2523")
	)
	(layers
		(0 "F.Cu" signal "TOP")
		(4 "In1.Cu" signal "L2GND")
		(6 "In2.Cu" signal "L3")
		(8 "In3.Cu" signal "L4VCC")
		(10 "In4.Cu" signal "L5VCC")
		(12 "In5.Cu" signal "L6")
		(14 "In6.Cu" signal "L7GND")
		(2 "B.Cu" signal "BOTTOM")
		(9 "F.Adhes" user "F.Adhesive")
		(11 "B.Adhes" user "B.Adhesive")
		(13 "F.Paste" user "Package Geometry/Pastemask Top")
		(15 "B.Paste" user "Package Geometry/Pastemask Bottom")
		(5 "F.SilkS" user "Ref Des/Silkscreen Top")
		(7 "B.SilkS" user "Ref Des/Silkscreen Bottom")
		(1 "F.Mask" user "Board Geometry/Soldermask Top")
		(3 "B.Mask" user "Board Geometry/Soldermask Bottom")
		(17 "Dwgs.User" user "User.Drawings")
		(19 "Cmts.User" user "User.Comments")
		(21 "Eco1.User" user "User.Eco1")
		(23 "Eco2.User" user "User.Eco2")
		(25 "Edge.Cuts" user "Board Geometry/Outline")
		(27 "Margin" user)
		(31 "F.CrtYd" user "Package Geometry/Place Bound Top")
		(29 "B.CrtYd" user "Package Geometry/Place Bound Bottom")
		(35 "F.Fab" user "Ref Des/Assembly Top")
		(33 "B.Fab" user "Ref Des/Assembly Bottom")
	)
	(footprint ""
		(layer "B.Cu")
		(at 117.545612 -205.867)
		(property "Reference" "SR886"
			(at 0 0 0)
			(layer "B.SilkS")
			(hide yes)
			(effects
				(font
					(size 1.27 1.27)
				)
				(justify mirror)
			)
		)
		(property "Value" "0R2J-2-GP"
			(at -0.064008 -3.993896 0)
			(unlocked yes)
			(layer "B.Fab")
			(hide yes)
			(effects
				(font
					(size 1.016 1.016)
					(thickness 0.1524)
				)
				(justify mirror)
			)
		)
		(property "Device Type" "R402H16"
			(at -0.064008 -5.517896 0)
			(unlocked yes)
			(layer "B.Fab")
			(hide yes)
			(effects
				(font
					(size 1.016 1.016)
					(thickness 0.1524)
				)
				(justify mirror)
			)
		)
		(duplicate_pad_numbers_are_jumpers no)
		(fp_line
			(start -0.508 -0.9398)
			(end 0.508 -0.9398)
			(stroke
				(width 0.1524)
				(type default)
			)
			(layer "B.SilkS")
		)
		(fp_line
			(start 0.508 -0.9398)
			(end 0.508 0.9398)
			(stroke
				(width 0.1524)
				(type default)
			)
			(layer "B.SilkS")
		)
		(fp_rect
			(start 0.508 0.9398)
			(end -0.508 -0.9398)
			(stroke
				(width 0)
				(type default)
			)
			(fill no)
			(layer "B.CrtYd")
		)
		(fp_rect
			(start 0.508 0.9398)
			(end -0.508 -0.9398)
			(stroke
				(width 0)
				(type default)
			)
			(fill no)
			(layer "B.Fab")
		)
		(pad "1" smd custom
			(at 0 -0.4445 180)
			(size 0.1397 0.1397)
			(layers "B.Cu" "B.Mask" "B.Paste")
			(net "SAS_HDD_REDV_SER_RX7_P")
			(options
				(clearance outline)
				(anchor circle)
			)
			(primitives
				(gr_poly
					(pts
						(arc
							(start -0.1778 0.2794)
							(mid -0.249642 0.249642)
							(end -0.2794 0.1778)
						)
						(arc
							(start -0.2794 -0.1778)
							(mid -0.249642 -0.249642)
							(end -0.1778 -0.2794)
						)
						(arc
							(start 0.1778 -0.2794)
							(mid 0.249642 -0.249642)
							(end 0.2794 -0.1778)
						)
						(arc
							(start 0.2794 0.1778)
							(mid 0.249642 0.249642)
							(end 0.1778 0.2794)
						)
					)
					(width 0)
					(fill yes)
				)
			)
		)
		(pad "2" smd custom
			(at 0 0.4445 180)
			(size 0.1397 0.1397)
			(layers "B.Cu" "B.Mask" "B.Paste")
			(net "SAS_HDD_CONN_RX7_P")
			(options
				(clearance outline)
				(anchor circle)
			)
			(primitives
				(gr_poly
					(pts
						(arc
							(start -0.1778 0.2794)
							(mid -0.249642 0.249642)
							(end -0.2794 0.1778)
						)
						(arc
							(start -0.2794 -0.1778)
							(mid -0.249642 -0.249642)
							(end -0.1778 -0.2794)
						)
						(arc
							(start 0.1778 -0.2794)
							(mid 0.249642 -0.249642)
							(end 0.2794 -0.1778)
						)
						(arc
							(start 0.2794 0.1778)
							(mid 0.249642 0.249642)
							(end 0.1778 0.2794)
						)
					)
					(width 0)
					(fill yes)
				)
			)
		)
	)
	(footprint ""
		(layer "B.Cu")
		(at 108.97616 -35.306 90)
		(property "Reference" "SC996"
			(at 0 0 90)
			(layer "B.SilkS")
			(hide yes)
			(effects
				(font
					(size 1.27 1.27)
				)
				(justify mirror)
			)
		)
		(property "Value" "SCD1U16V2KX-3GP"
			(at -1.1811 -2.7051 90)
			(unlocked yes)
			(layer "B.Fab")
			(hide yes)
			(effects
				(font
					(size 1.016 1.016)
					(thickness 0.1524)
				)
				(justify mirror)
			)
		)
		(property "Device Type" "C402H22"
			(at -1.1811 -4.2291 90)
			(unlocked yes)
			(layer "B.Fab")
			(hide yes)
			(effects
				(font
					(size 1.016 1.016)
					(thickness 0.1524)
				)
				(justify mirror)
			)
		)
		(duplicate_pad_numbers_are_jumpers no)
		(fp_rect
			(start 0.4318 0.9525)
			(end -0.4318 -0.9525)
			(stroke
				(width 0)
				(type default)
			)
			(fill no)
			(layer "B.CrtYd")
		)
		(fp_rect
			(start 0.4318 0.9525)
			(end -0.4318 -0.9525)
			(stroke
				(width 0)
				(type default)
			)
			(fill no)
			(layer "B.Fab")
		)
		(pad "1" smd custom
			(at 0 -0.4445 270)
			(size 0.1524 0.1524)
			(layers "B.Cu" "B.Mask" "B.Paste")
			(net "P1V8_C")
			(options
				(clearance outline)
				(anchor circle)
			)
			(primitives
				(gr_poly
					(pts
						(arc
							(start 0.3048 0.2032)
							(mid 0.275042 0.275042)
							(end 0.2032 0.3048)
						)
						(arc
							(start -0.2032 0.3048)
							(mid -0.275042 0.275042)
							(end -0.3048 0.2032)
						)
						(arc
							(start -0.3048 -0.2032)
							(mid -0.275042 -0.275042)
							(end -0.2032 -0.3048)
						)
						(arc
							(start 0.2032 -0.3048)
							(mid 0.275042 -0.275042)
							(end 0.3048 -0.2032)
						)
					)
					(width 0)
					(fill yes)
				)
			)
		)
		(pad "2" smd custom
			(at 0 0.4445 270)
			(size 0.1524 0.1524)
			(layers "B.Cu" "B.Mask" "B.Paste")
			(net "GND")
			(options
				(clearance outline)
				(anchor circle)
			)
			(primitives
				(gr_poly
					(pts
						(arc
							(start 0.3048 0.2032)
							(mid 0.275042 0.275042)
							(end 0.2032 0.3048)
						)
						(arc
							(start -0.2032 0.3048)
							(mid -0.275042 0.275042)
							(end -0.3048 0.2032)
						)
						(arc
							(start -0.3048 -0.2032)
							(mid -0.275042 -0.275042)
							(end -0.2032 -0.3048)
						)
						(arc
							(start 0.2032 -0.3048)
							(mid 0.275042 -0.275042)
							(end 0.3048 -0.2032)
						)
					)
					(width 0)
					(fill yes)
				)
			)
		)
	)
	(footprint ""
		(layer "B.Cu")
		(at 117.475 -39.116)
		(property "Reference" "STP132"
			(at 0 0 0)
			(layer "B.SilkS")
			(hide yes)
			(effects
				(font
					(size 1.27 1.27)
				)
				(justify mirror)
			)
		)
		(property "Value" "TPAD28"
			(at -0.0127 -1.8034 0)
			(unlocked yes)
			(layer "B.Fab")
			(hide yes)
			(effects
				(font
					(size 1.016 1.016)
					(thickness 0.1524)
				)
				(justify mirror)
			)
		)
		(property "Device Type" "TPAD28"
			(at -0.0127 -3.3274 0)
			(unlocked yes)
			(layer "B.Fab")
			(hide yes)
			(effects
				(font
					(size 1.016 1.016)
					(thickness 0.1524)
				)
				(justify mirror)
			)
		)
		(duplicate_pad_numbers_are_jumpers no)
		(fp_poly
			(pts
				(arc
					(start 0.3556 0)
					(mid -0.3556 0)
					(end 0.3556 0)
				)
			)
			(stroke
				(width 0)
				(type default)
			)
			(fill no)
			(layer "B.CrtYd")
		)
		(fp_poly
			(pts
				(arc
					(start 0.6096 0)
					(mid -0.6096 0)
					(end 0.6096 0)
				)
			)
			(stroke
				(width 0)
				(type default)
			)
			(fill no)
			(layer "B.Fab")
		)
		(pad "1" smd circle
			(at 0 0 180)
			(size 0.7112 0.7112)
			(layers "B.Cu" "B.Mask" "B.Paste")
			(net "IOC_GPIO_15")
		)
	)
	(footprint ""
		(layer "B.Cu")
		(at 103.359966 -43.307 90)
		(property "Reference" "SC1028"
			(at 0 0 90)
			(layer "B.SilkS")
			(hide yes)
			(effects
				(font
					(size 1.27 1.27)
				)
				(justify mirror)
			)
		)
		(property "Value" "SC1U10V2KX-4-GP"
			(at -1.1811 -2.7051 90)
			(unlocked yes)
			(layer "B.Fab")
			(hide yes)
			(effects
				(font
					(size 1.016 1.016)
					(thickness 0.1524)
				)
				(justify mirror)
			)
		)
		(property "Device Type" "C402H22"
			(at -1.1811 -4.2291 90)
			(unlocked yes)
			(layer "B.Fab")
			(hide yes)
			(effects
				(font
					(size 1.016 1.016)
					(thickness 0.1524)
				)
				(justify mirror)
			)
		)
		(duplicate_pad_numbers_are_jumpers no)
		(fp_rect
			(start 0.4318 0.9525)
			(end -0.4318 -0.9525)
			(stroke
				(width 0)
				(type default)
			)
			(fill no)
			(layer "B.CrtYd")
		)
		(fp_rect
			(start 0.4318 0.9525)
			(end -0.4318 -0.9525)
			(stroke
				(width 0)
				(type default)
			)
			(fill no)
			(layer "B.Fab")
		)
		(pad "1" smd custom
			(at 0 -0.4445 270)
			(size 0.1524 0.1524)
			(layers "B.Cu" "B.Mask" "B.Paste")
			(net "P0V955_C")
			(options
				(clearance outline)
				(anchor circle)
			)
			(primitives
				(gr_poly
					(pts
						(arc
							(start 0.3048 0.2032)
							(mid 0.275042 0.275042)
							(end 0.2032 0.3048)
						)
						(arc
							(start -0.2032 0.3048)
							(mid -0.275042 0.275042)
							(end -0.3048 0.2032)
						)
						(arc
							(start -0.3048 -0.2032)
							(mid -0.275042 -0.275042)
							(end -0.2032 -0.3048)
						)
						(arc
							(start 0.2032 -0.3048)
							(mid 0.275042 -0.275042)
							(end 0.3048 -0.2032)
						)
					)
					(width 0)
					(fill yes)
				)
			)
		)
		(pad "2" smd custom
			(at 0 0.4445 270)
			(size 0.1524 0.1524)
			(layers "B.Cu" "B.Mask" "B.Paste")
			(net "GND")
			(options
				(clearance outline)
				(anchor circle)
			)
			(primitives
				(gr_poly
					(pts
						(arc
							(start 0.3048 0.2032)
							(mid 0.275042 0.275042)
							(end 0.2032 0.3048)
						)
						(arc
							(start -0.2032 0.3048)
							(mid -0.275042 0.275042)
							(end -0.3048 0.2032)
						)
						(arc
							(start -0.3048 -0.2032)
							(mid -0.275042 -0.275042)
							(end -0.2032 -0.3048)
						)
						(arc
							(start 0.2032 -0.3048)
							(mid 0.275042 -0.275042)
							(end 0.3048 -0.2032)
						)
					)
					(width 0)
					(fill yes)
				)
			)
		)
	)
	(footprint ""
		(layer "B.Cu")
		(at 107.07116 -35.306 90)
		(property "Reference" "SC997"
			(at 0 0 90)
			(layer "B.SilkS")
			(hide yes)
			(effects
				(font
					(size 1.27 1.27)
				)
				(justify mirror)
			)
		)
		(property "Value" "SCD1U16V2KX-3GP"
			(at -1.1811 -2.7051 90)
			(unlocked yes)
			(layer "B.Fab")
			(hide yes)
			(effects
				(font
					(size 1.016 1.016)
					(thickness 0.1524)
				)
				(justify mirror)
			)
		)
		(property "Device Type" "C402H22"
			(at -1.1811 -4.2291 90)
			(unlocked yes)
			(layer "B.Fab")
			(hide yes)
			(effects
				(font
					(size 1.016 1.016)
					(thickness 0.1524)
				)
				(justify mirror)
			)
		)
		(duplicate_pad_numbers_are_jumpers no)
		(fp_rect
			(start 0.4318 0.9525)
			(end -0.4318 -0.9525)
			(stroke
				(width 0)
				(type default)
			)
			(fill no)
			(layer "B.CrtYd")
		)
		(fp_rect
			(start 0.4318 0.9525)
			(end -0.4318 -0.9525)
			(stroke
				(width 0)
				(type default)
			)
			(fill no)
			(layer "B.Fab")
		)
		(pad "1" smd custom
			(at 0 -0.4445 270)
			(size 0.1524 0.1524)
			(layers "B.Cu" "B.Mask" "B.Paste")
			(net "P1V8_C")
			(options
				(clearance outline)
				(anchor circle)
			)
			(primitives
				(gr_poly
					(pts
						(arc
							(start 0.3048 0.2032)
							(mid 0.275042 0.275042)
							(end 0.2032 0.3048)
						)
						(arc
							(start -0.2032 0.3048)
							(mid -0.275042 0.275042)
							(end -0.3048 0.2032)
						)
						(arc
							(start -0.3048 -0.2032)
							(mid -0.275042 -0.275042)
							(end -0.2032 -0.3048)
						)
						(arc
							(start 0.2032 -0.3048)
							(mid 0.275042 -0.275042)
							(end 0.3048 -0.2032)
						)
					)
					(width 0)
					(fill yes)
				)
			)
		)
		(pad "2" smd custom
			(at 0 0.4445 270)
			(size 0.1524 0.1524)
			(layers "B.Cu" "B.Mask" "B.Paste")
			(net "GND")
			(options
				(clearance outline)
				(anchor circle)
			)
			(primitives
				(gr_poly
					(pts
						(arc
							(start 0.3048 0.2032)
							(mid 0.275042 0.275042)
							(end 0.2032 0.3048)
						)
						(arc
							(start -0.2032 0.3048)
							(mid -0.275042 0.275042)
							(end -0.3048 0.2032)
						)
						(arc
							(start -0.3048 -0.2032)
							(mid -0.275042 -0.275042)
							(end -0.2032 -0.3048)
						)
						(arc
							(start 0.2032 -0.3048)
							(mid 0.275042 -0.275042)
							(end 0.3048 -0.2032)
						)
					)
					(width 0)
					(fill yes)
				)
			)
		)
	)
	(footprint ""
		(layer "B.Cu")
		(at 164.338 -89.281)
		(property "Reference" "PC182"
			(at 0 0 0)
			(layer "B.SilkS")
			(hide yes)
			(effects
				(font
					(size 1.27 1.27)
				)
				(justify mirror)
			)
		)
		(property "Value" "SC47U6D3V5MX-1-GP"
			(at 0.0762 -6.1214 0)
			(unlocked yes)
			(layer "B.Fab")
			(hide yes)
			(effects
				(font
					(size 1.016 1.016)
					(thickness 0.1524)
				)
				(justify mirror)
			)
		)
		(property "Device Type" "C805H54"
			(at 0.0762 -8.1534 0)
			(unlocked yes)
			(layer "B.Fab")
			(hide yes)
			(effects
				(font
					(size 1.016 1.016)
					(thickness 0.1524)
				)
				(justify mirror)
			)
		)
		(duplicate_pad_numbers_are_jumpers no)
		(fp_line
			(start -0.635 0)
			(end 0.635 0)
			(stroke
				(width 0.508)
				(type default)
			)
			(layer "B.SilkS")
		)
		(fp_rect
			(start 0.9652 1.778)
			(end -0.9652 -1.778)
			(stroke
				(width 0)
				(type default)
			)
			(fill no)
			(layer "B.CrtYd")
		)
		(fp_poly
			(pts
				(xy 0.9652 -1.778) (xy -0.9652 -1.778) (xy -0.9652 1.778) (xy 0.9652 1.778)
			)
			(stroke
				(width 0)
				(type default)
			)
			(fill no)
			(layer "B.Fab")
		)
		(pad "1" smd rect
			(at 0 -0.9652 180)
			(size 1.397 1.143)
			(layers "B.Cu" "B.Mask" "B.Paste")
			(net "P0V9_E")
		)
		(pad "2" smd rect
			(at 0 0.9652 180)
			(size 1.397 1.143)
			(layers "B.Cu" "B.Mask" "B.Paste")
			(net "GND")
		)
	)
	(footprint ""
		(layer "B.Cu")
		(at 118.37797 -82.931 -90)
		(property "Reference" "SC1223"
			(at 0 0 90)
			(layer "B.SilkS")
			(hide yes)
			(effects
				(font
					(size 1.27 1.27)
				)
				(justify mirror)
			)
		)
		(property "Value" "SCD1U6D3V1KX-GP"
			(at 2.8321 -1.7399 270)
			(unlocked yes)
			(layer "B.Fab")
			(hide yes)
			(effects
				(font
					(size 1.016 1.016)
					(thickness 0.1524)
				)
				(justify mirror)
			)
		)
		(property "Device Type" "C0201H13"
			(at 2.8321 -3.2639 270)
			(unlocked yes)
			(layer "B.Fab")
			(hide yes)
			(effects
				(font
					(size 1.016 1.016)
					(thickness 0.1524)
				)
				(justify mirror)
			)
		)
		(duplicate_pad_numbers_are_jumpers no)
		(fp_rect
			(start 0.2794 0.6477)
			(end -0.2794 -0.6477)
			(stroke
				(width 0)
				(type default)
			)
			(fill no)
			(layer "B.CrtYd")
		)
		(fp_rect
			(start 0.2794 0.6477)
			(end -0.2794 -0.6477)
			(stroke
				(width 0)
				(type default)
			)
			(fill no)
			(layer "B.Fab")
		)
		(pad "1" smd custom
			(at 0 -0.2794 90)
			(size 0.0762 0.0762)
			(layers "B.Cu" "B.Mask" "B.Paste")
			(net "P1V8_E")
			(options
				(clearance outline)
				(anchor circle)
			)
			(primitives
				(gr_poly
					(pts
						(arc
							(start 0.1524 0.127)
							(mid 0.137521 0.162921)
							(end 0.1016 0.1778)
						)
						(arc
							(start -0.1016 0.1778)
							(mid -0.137521 0.162921)
							(end -0.1524 0.127)
						)
						(arc
							(start -0.1524 -0.127)
							(mid -0.137521 -0.162921)
							(end -0.1016 -0.1778)
						)
						(arc
							(start 0.1016 -0.1778)
							(mid 0.137521 -0.162921)
							(end 0.1524 -0.127)
						)
					)
					(width 0)
					(fill yes)
				)
			)
		)
		(pad "2" smd custom
			(at 0 0.2794 90)
			(size 0.0762 0.0762)
			(layers "B.Cu" "B.Mask" "B.Paste")
			(net "GND")
			(options
				(clearance outline)
				(anchor circle)
			)
			(primitives
				(gr_poly
					(pts
						(arc
							(start 0.1524 0.127)
							(mid 0.137521 0.162921)
							(end 0.1016 0.1778)
						)
						(arc
							(start -0.1016 0.1778)
							(mid -0.137521 0.162921)
							(end -0.1524 0.127)
						)
						(arc
							(start -0.1524 -0.127)
							(mid -0.137521 -0.162921)
							(end -0.1016 -0.1778)
						)
						(arc
							(start 0.1016 -0.1778)
							(mid 0.137521 -0.162921)
							(end 0.1524 -0.127)
						)
					)
					(width 0)
					(fill yes)
				)
			)
		)
	)
	(footprint ""
		(layer "B.Cu")
		(at 180.013864 -31.187136 90)
		(property "Reference" "C223"
			(at 0 0 90)
			(layer "B.SilkS")
			(hide yes)
			(effects
				(font
					(size 1.27 1.27)
				)
				(justify mirror)
			)
		)
		(property "Value" "SCD1U16V2KX-3GP"
			(at -1.1811 -2.7051 90)
			(unlocked yes)
			(layer "B.Fab")
			(hide yes)
			(effects
				(font
					(size 1.016 1.016)
					(thickness 0.1524)
				)
				(justify mirror)
			)
		)
		(property "Device Type" "C402H22"
			(at -1.1811 -4.2291 90)
			(unlocked yes)
			(layer "B.Fab")
			(hide yes)
			(effects
				(font
					(size 1.016 1.016)
					(thickness 0.1524)
				)
				(justify mirror)
			)
		)
		(duplicate_pad_numbers_are_jumpers no)
		(fp_rect
			(start 0.4318 0.9525)
			(end -0.4318 -0.9525)
			(stroke
				(width 0)
				(type default)
			)
			(fill no)
			(layer "B.CrtYd")
		)
		(fp_rect
			(start 0.4318 0.9525)
			(end -0.4318 -0.9525)
			(stroke
				(width 0)
				(type default)
			)
			(fill no)
			(layer "B.Fab")
		)
		(pad "1" smd custom
			(at 0 -0.4445 270)
			(size 0.1524 0.1524)
			(layers "B.Cu" "B.Mask" "B.Paste")
			(net "PHY_AVDD")
			(options
				(clearance outline)
				(anchor circle)
			)
			(primitives
				(gr_poly
					(pts
						(arc
							(start 0.3048 0.2032)
							(mid 0.275042 0.275042)
							(end 0.2032 0.3048)
						)
						(arc
							(start -0.2032 0.3048)
							(mid -0.275042 0.275042)
							(end -0.3048 0.2032)
						)
						(arc
							(start -0.3048 -0.2032)
							(mid -0.275042 -0.275042)
							(end -0.2032 -0.3048)
						)
						(arc
							(start 0.2032 -0.3048)
							(mid 0.275042 -0.275042)
							(end 0.3048 -0.2032)
						)
					)
					(width 0)
					(fill yes)
				)
			)
		)
		(pad "2" smd custom
			(at 0 0.4445 270)
			(size 0.1524 0.1524)
			(layers "B.Cu" "B.Mask" "B.Paste")
			(net "GND")
			(options
				(clearance outline)
				(anchor circle)
			)
			(primitives
				(gr_poly
					(pts
						(arc
							(start 0.3048 0.2032)
							(mid 0.275042 0.275042)
							(end 0.2032 0.3048)
						)
						(arc
							(start -0.2032 0.3048)
							(mid -0.275042 0.275042)
							(end -0.3048 0.2032)
						)
						(arc
							(start -0.3048 -0.2032)
							(mid -0.275042 -0.275042)
							(end -0.2032 -0.3048)
						)
						(arc
							(start 0.2032 -0.3048)
							(mid 0.275042 -0.275042)
							(end 0.3048 -0.2032)
						)
					)
					(width 0)
					(fill yes)
				)
			)
		)
	)
	(footprint ""
		(layer "B.Cu")
		(at 108.72216 -33.782)
		(property "Reference" "STP134"
			(at 0 0 0)
			(layer "B.SilkS")
			(hide yes)
			(effects
				(font
					(size 1.27 1.27)
				)
				(justify mirror)
			)
		)
		(property "Value" "TPAD28"
			(at -0.0127 -1.8034 0)
			(unlocked yes)
			(layer "B.Fab")
			(hide yes)
			(effects
				(font
					(size 1.016 1.016)
					(thickness 0.1524)
				)
				(justify mirror)
			)
		)
		(property "Device Type" "TPAD28"
			(at -0.0127 -3.3274 0)
			(unlocked yes)
			(layer "B.Fab")
			(hide yes)
			(effects
				(font
					(size 1.016 1.016)
					(thickness 0.1524)
				)
				(justify mirror)
			)
		)
		(duplicate_pad_numbers_are_jumpers no)
		(fp_poly
			(pts
				(arc
					(start 0.3556 0)
					(mid -0.3556 0)
					(end 0.3556 0)
				)
			)
			(stroke
				(width 0)
				(type default)
			)
			(fill no)
			(layer "B.CrtYd")
		)
		(fp_poly
			(pts
				(arc
					(start 0.6096 0)
					(mid -0.6096 0)
					(end 0.6096 0)
				)
			)
			(stroke
				(width 0)
				(type default)
			)
			(fill no)
			(layer "B.Fab")
		)
		(pad "1" smd circle
			(at 0 0 180)
			(size 0.7112 0.7112)
			(layers "B.Cu" "B.Mask" "B.Paste")
			(net "IOC_GPIO_5")
		)
	)
)
